# GT_SCM_BOM_20230501.xlsx — BOM Sharing Template (bom)
| Part Description | Manufacturer | Manufacturing Part Number | Quantity | Location (CRD) | HSC/VR |
| ICOTHER(256P)LCMXO3LF-2100C-5BG256(CABGA | LSC | LCMXO3LF-2100C-5BG256C | 1 | U25 |  |
| IC(624P)AST2600A3-GP(TFBGA) | APD | AST2600A3-GP | 1 | U5 |  |
| IC SDRAM(96P)K4A8G165WC-BCTD(FBGA)QBCON | SAM | K4A8G165WC-BCTD | 1 | U1 |  |
| IC(8P)M24128-BWDW6TP(TSSOP) | SGT | M24128-BWDW6TP | 1 | U19 |  |
| IC OTHER(16P)IDTQS3VH257PAG(TSSOP) | IDT | IDTQS3VH257PAG | 2 | U21,U30 |  |
| IC OTHER(6P)NCP380HSNAJAAT1G(TSOP-6) | ONS | NCP380HSNAJAAT1G | 1 | U10 |  |
| IC CTRL(13P)NB695GD-Z(QFN-13) | MPS | NB695GD-Z | 2 | PU41,PU42 |  |
| IC(5P) SN74LVC1G14DCKR(SC70) | TIC | SN74LVC1G14DCKR | 1 | U55 |  |
| IC OTHER (5P)MC74VHC1G32DTT1G(SOT-23) | ONS | MC74VHC1G32DTT1G | 4 | U9,U42,U49,U58 |  |
| IC(5P) 74LVC1G66GV(SOT753) | PHI | 74LVC1G66GV | 1 | U28 |  |
| IC OTHER(5P)AP2205-W5-7(SOT25) | DDS | AP2205-W5-7 | 1 | U56 |  |
| IC OTHER(6P)74LVC2G07DW-7(SOT-363) | DDS | 74LVC2G07DW-7 | 3 | U6,U24,U47 |  |
| IC OTHER(20P) PI3PCIE3212ZBEX(QFN) | PIM | PI3PCIE3212ZBEX | 1 | U22 |  |
| IC OTHER(8P)FSA3357K8X(US8) | FAC | FSA3357K8X | 2 | U2,U3 |  |
| IC OTHER(6P)TPS3808G01DBVR(SOT23) | TIC | TPS3808G01DBVR | 1 | U43 |  |
| IC CTRL(14P)MPQ8626GD-Z(QFN) | MPS | MPQ8626GD-Z | 1 | PU1 |  |
| IC CTRL(21P)MPQ8633AGLE-C807-Z(QFN) | MPS | MPQ8633AGLE-C807-Z | 1 | PU38 |  |
| IC OTHER(10P) RT9059GQW(WDFN) | RTK | RT9059GQW | 2 | U39,U41 |  |
| IC OTHER (8P) PCA9517ADP(TSSOP8) | NXP | PCA9517ADP | 1 | U37 |  |
| IC OTHER(5P)AP22811AW5-7(SOT25) | DDS | AP22811AW5-7 | 1 | U14 |  |
| IC OTHER(5P) 74LVC1G17GW(TSSOP) | NXP | 74LVC1G17GW | 1 | U32 |  |
| IC OTHER(8P) 74LVC1G74DP (TSSOP8) | NXP | 74LVC1G74DP | 1 | U54 |  |
| IC(5P) 74HC1G126GW(SOT353)EP | PHI | 74HC1G126GW | 4 | U26,U29,U33,U36 |  |
| IC OTHER(5P) 74LVC1G126SE-7 (SOT353) | DDS | 74LVC1G126SE-7 | 1 | U8 |  |
| IC OTHER (4P) PRTR5V0U2X (SOT143B) | NXP | PRTR5V0U2X | 1 | U38 |  |
| IC(6P) NC7SB3157P6X(SC70-6) | FAC | NC7SB3157P6X | 4 | U7,U20,U50,U51 |  |
| IC(5P)74LVC1G07W5-7(SOT25) | DDS | 74LVC1G07W5-7 | 1 | U23 |  |
| IC(5P) 74LVC1G07GW(SOT353) | PHI | 74LVC1G07GW | 2 | U31,U57 |  |
| IC(5P) 74LVC1G08GW (SC70-5) | PHI | 74LVC1G08GW | 4 | U15,U18,U52,U53 |  |
| TRANS SMD MMBT3904-7-F(40V,200MA,8W) | DDS | MMBT3904-7-F | 2 | Q1,Q3 |  |
| TRANS MOS BSS138K(50V,0.22A,0.35W) | FAC | BSS138K | 1 | U12 |  |
| TRANS MOSFET PJT138K(50V,0.36A,0.236W) | PJT | PJT138K | 2 | Q9,Q13 |  |
| TRANS MOS NTGS4141NT1G(30V,7.0A,TSOP6) | ONS | NTGS4141NT1G | 1 | Q5 |  |
| TRANS MOS DMG6968U-7(20V,6.5A,1.3W)SOT23 | DDS | DMG6968U-7 | 1 | Q10 |  |
| TRANS MOS 2N7002KDW(60V115MA,0.2W)SOT363 | PJT | 2N7002KDW | 2 | Q2,Q12 |  |
| TRANS MOS NX7002AK(60V,0.19A,0.325W)SMD | NXP | NX7002AK | 1 | Q11 |  |
| TRANS MOS 2N7002A-7(60V,0.115A,0.25W) | DDS | 2N7002A-7 | 3 | Q6,Q7,Q8 |  |
| DIODE SMD SDMK0340L-7-F(40V,30MA) | DDS | SDMK0340L-7-F | 1 | D17 |  |
| DIODE ARRAY DT1240E-04LP-7 (3.3V) | DDS | DT1240E-04LP-7 | 3 | U27,U34,U35 |  |
| DIODE SMD 1N5819HW-7-F(40V.1A.SOD123) | DDS | 1N5819HW-7-F | 1 | D20 |  |
| DIODE SMD BAS70-05-7-F(70V,SHTKY,SOT-23) | DDS | BAS70-05-7-F | 1 | U48 |  |
| DIODE SMD BAT54C(30V,0.2A,SCHOTTKY) | PJT | BAT54C | 1 | U11 |  |
| DIODE SMD SS0530(30V,0.5A)SOD-123 | PJT | SS0530 | 1 | D11 |  |
| LED SMD(2P) BLUE(LTST-C281TBKT-5A) | LIT | LTST-C281TBKT-5A | 2 | D18,D19 |  |
| LED DIP(2P)BLUE (LTLR42FTBGAJH213T) | LOE | LTLR42FTBGAJH213T | 4 | D14,D15,D21,D22 |  |
| LED SMD(2P) GREEN(19-213/GVC-AMNB/3T) | EVL | 19-213/GVC-AMNB/3T | 5 | D0,D1,D2,D3,D8 |  |
| LED SMD(2P) RED (19-217/R6C-P1Q2/3T) | EVL | 19-217/R6C-P1Q2/3T | 4 | D4,D5,D6,D7 |  |
| LED DIP(2P)YELLOW(LTL-R42FSFADH213T) | LOE | LTL-R42FSFADH213T | 1 | D13 |  |
| OSC SMD 25MHZ(+25PPM,3.3V)7X25000018 | TXC | 7X25000018 | 2 | OSC1,OSC2 |  |
| CAP CHIP 10PF 50V(+-1%,NPO,0402) | JDI | 500R07S100FV4T | 2 | C211,C212 |  |
| CAP CHIP 68P 50V(+5%.COG.0402) | API | C1005NP0680JGT | 1 | PC272 |  |
| CAP CHIP 100P 50V(+5%,NPO,0402) | API | C1005NP0101JGT | 3 | C9,C275,PC239 |  |
| CAP CHIP 470P 50V(+-10%,X7R,0402) | API | C1005X7R471KGT | 5 | C172,C178,C179,C324,C326 |  |
| CAP CHIP 2200P 50V(+10%,X7R,0402) | API | C1005X7R222KGT | 2 | C63,C173 |  |
| CAP CHIP 3300P 50V(+-10%,X7R,0402) | API | C1005X7R332KGT | 1 | PC273 |  |
| CAP CHIP 0.01U 50V(+10%,X7R,0402) | API | C1005X7R103KGT | 8 | C133,C134,C135,C136,C137,C138,C170,C246 |  |
| CAP CHIP 0.1U 25V(+10%,X7R,0402) | EYT | C0402X7R104K250NTN | 174 | C6,C7,C8,C10,C11,C13,C14,C17,C18,C19,C20,C22,C23,C24,C25,C26,C27,C31,C33,C34,C36,C37,C39,C41,C45,C49,C50,C51,C54,C57,C59,C65,C66,C68,C69,C70,C71,C72,C73,C74,C76,C77,C79,C81,C82,C83,C84,C85,C86,C87,C88,C89,C91,C92,C93,C94,C95,C96,C97,C98,C99,C100,C101,C102,C103,C105,C107,C109,C112,C130,C139,C140,C141,C144,C146,C148,C149,C152,C157,C158,C159,C160,C162,C167,C168,C175,C180,C181,C187,C188,C189,C190,C191,C192,C193,C197,C200,C201,C202,C203,C217,C219,C220,C221,C222,C225,C231,C236,C237,C240,C241,C242,C243,C245,C247,C249,C250,C251,C253,C254,C255,C257,C260,C261,C262,C263,C264,C266,C268,C269,C271,C272,C274,C276,C278,C279,C280,C284,C290,C291,C294,C295,C296,C297,C298,C299,C300,C301,C302,C303,C304,C307,C309,C311,C312,C313,C314,C318,C321,C336,C337,C500,C501,PC205,PC210,PC212,PC223,PC225,PC253,PC255,PC263,PC266,PC271 |  |
| CAP CHIP 0.22U 16V(10%,X7R,0402) | MUR | GRM155R71C224K | 5 | C12,PC216,PC224,PC254,PC264 |  |
| CAP CHIP 1UF 25V(+10%,X6S,0402) | MUR | GRM155C81E105K | 65 | C2,C3,C4,C5,C30,C32,C35,C38,C43,C46,C47,C48,C52,C53,C56,C58,C60,C61,C62,C64,C67,C75,C78,C80,C90,C104,C106,C108,C110,C111,C114,C115,C116,C117,C119,C122,C127,C128,C129,C145,C161,C164,C165,C166,C176,C195,C196,C198,C199,C216,C218,C226,C244,C256,C277,C282,C287,C292,C305,C310,C335,PC208,PC221,PC250,PC260 |  |
| CAP CHIP 2.2UF 10V(+-10%,X6S,0402) | MUR | GRM155C81A225K | 1 | C227 |  |
| CAP CHIP 4.7UF 25V(+10%,X6S,0603) | API | C1608X6S475KFT | 3 | C1,C40,C44 |  |
| CAP CHIP 10UF 6.3V(+20%,X6S,0402) | KYO | CM05X6S106M06AH | 6 | C15,C16,C143,C215,C224,C248 |  |
| CAP CHIP 10U 16V(+20%,X6S,0603) | MUR | GRM188C81C106M | 2 | C163,C194 |  |
| CAP CHIP 10U 25V(+10%,X6S,0805,H1.25) | MKP | MAG05X6S1E106K | 8 | C142,C288,C289,C293,PC251,PC252,PC261,PC262 |  |
| CAP CHIP 22U 6.3V(+20%,X6S,0603) | API | C1608X6S226MCT | 12 | C42,C55,C113,C118,C120,C121,C123,C124,C125,C126,C131,C132 |  |
| CAP CHIP 22U 10V(+20%,X6S,0805) | MUR | GRM21BC81A226M | 9 | C171,PC213,PC214,PC215,PC217,PC226,PC227,PC228,PC229 |  |
| CAP CHIP 22UF 16V(+20%,X6S,0805)MUR | MUR | GRM21BC81C226M | 7 | C265,C329,C330,PC206,PC207,PC218,PC219 |  |
| CAP CHIP 22U 4V(+-20%,X6S,0805) | MKP | MAG05X6S0G226M | 8 | PC256,PC257,PC258,PC259,PC267,PC268,PC269,PC270 |  |
| CAP CHIP 47U 6.3V(+20%,X6S,1206) | MUR | GRM31CC80J476M | 2 | C177,C327 |  |
| RES CHIP 2.2 1/16W +1%(0402)EF | CYN | RR0510S-2R2-FTF | 1 | R415 |  |
| RES CHIP 5.1 1/16W +5%(0402)EF | CYN | RR0510S-5R1-JTF | 2 | PR539,PR541 |  |
| RES CHIP 0 1/16W +5%(0402)EF | CYN | RR0510S-000-XTF | 154 | PR193,PR274,R2,R3,R18,R19,R20,R30,R35,R39,R49,R57,R83,R84,R85,R86,R95,R97,R98,R99,R109,R110,R113,R134,R135,R155,R182,R183,R207,R213,R217,R218,R220,R231,R275,R276,R277,R279,R281,R282,R292,R293,R294,R301,R304,R305,R307,R308,R316,R381,R382,R385,R386,R392,R393,R395,R398,R399,R450,R451,R453,R471,R500,R503,R505,R525,R527,R528,R544,R545,R546,R560,R566,R616,R618,R626,R629,R632,R636,R637,R666,R668,R669,R670,R671,R672,R673,R674,R675,R676,R695,R696,R697,R698,R700,R701,R702,R703,R707,R708,R720,R721,R722,R726,R728,R731,R732,R733,R734,R779,R783,R804,R822,R838,R847,R853,R882,R900,R901,R902,R903,R105,R114,R318,R323,R447,R454,R574,R577,R578,R579,R634,R746,R747,R748,R10,R51,R271,R272,R303,R317,R320,R321,R322,R379,R397,R432,R456,R457,R519,R571,R575,R898,R899 |  |
| RES CHIP 10 1/16W +1%(0402)EF | CYN | RR0510S-100-FTF | 3 | R21,R24,R26 |  |
| RES CHIP 22 1/16W +1%(0402)EF | YGO | RC0402FR-0722RP | 13 | R128,R129,R130,R131,R171,R172,R173,R498,R499,R860,R861,R862,R863 |  |
| RES CHIP 33.2 1/16W +1%(0402)EF | CYN | RR0510S-33R2-FTF | 201 | R28,R29,R33,R36,R37,R46,R47,R60,R65,R70,R71,R93,R96,R100,R102,R104,R111,R112,R119,R120,R121,R122,R132,R133,R137,R139,R142,R143,R144,R146,R147,R148,R150,R151,R152,R153,R157,R158,R159,R160,R162,R165,R166,R168,R170,R174,R175,R176,R177,R178,R179,R180,R185,R187,R199,R201,R215,R221,R222,R223,R224,R236,R237,R242,R243,R300,R302,R309,R310,R311,R388,R390,R394,R401,R402,R405,R407,R421,R423,R424,R425,R426,R427,R433,R439,R442,R443,R444,R448,R449,R455,R458,R460,R461,R465,R466,R469,R479,R481,R482,R483,R484,R485,R486,R489,R494,R501,R509,R510,R511,R512,R513,R514,R515,R516,R517,R518,R547,R548,R549,R550,R551,R552,R553,R555,R556,R559,R562,R567,R570,R580,R582,R583,R584,R585,R589,R590,R594,R639,R643,R644,R688,R693,R705,R713,R715,R724,R725,R752,R757,R759,R760,R761,R762,R763,R766,R799,R801,R802,R807,R812,R813,R824,R826,R827,R836,R840,R849,R850,R859,R864,R880,R884,R123,R434,R436,R437,R445,R536,R537,R635,R638,R691,R718,R769,R841,R263,R270,R435,R459,R690,R750,R767,R773,R825,R833,R837 |  |
| RES CHIP 49.9 1/16W +1%(0402)EF | CYN | RR0510S-49R9-FTF | 5 | R108,R192,R216,R409,R410 |  |
| RES CHIP 60.4 1/16W +1%(0402)EF | CYN | RR0510S-60R4-FTF | 2 | R7,R8 |  |
| RES CHIP 68.1 1/16W +1%(0402)EF | CYN | RR0510S-68R1-FTF | 1 | R852 |  |
| RES CHIP 75 1/16W +1%(0402)EF | CYN | RR0510S-750-FTF | 2 | R283,R284 |  |
| RES CHIP 90.9 1/16W +-1%(0402)EF | CYN | RR0510S-90R9-FTF | 1 | R468 |  |
| RES CHIP 100 1/16W +1%(0402)EF | CYN | RR0510S-101-FTF | 12 | R125,R380,R411,R412,R413,R529,R530,R694,R225,R384,R565,R628 |  |
| RES CHIP 120 1/16W +1%(0402)EF | CYN | RR0510S-121-FTF | 48 | R326,R327,R328,R329,R330,R331,R332,R333,R334,R335,R336,R337,R338,R339,R340,R341,R342,R343,R344,R345,R346,R347,R348,R349,R351,R352,R353,R354,R355,R356,R357,R358,R359,R360,R361,R362,R363,R364,R365,R366,R367,R368,R369,R370,R371,R372,R373,R374 |  |
| RES CHIP 150 1/16W +1%(0402)EF | CYN | RR0510S-151-FTF | 7 | R22,R23,R25,R87,R88,R89,R420 |  |
| RES CHIP 200 1/16W +1%(0402)EF | CYN | RR0510S-201-FTF | 1 | R879 |  |
| RES CHIP 220 1/16W +1%(0402)EF | CYN | RR0510S-221-FTF | 4 | R43,R80,R568,R569 |  |
| RES CHIP 240 1/16W +1%(0402)EF | CYN | RR0510S-241-FTF | 2 | R6,R127 |  |
| RES CHIP 316 1/16W +1%(0402)EF | CYN | RR0510S-3160-FTF | 3 | R107,R286,R389 |  |
| RES CHIP 330 1/16W +1%(0402)EF | CYN | RR0510S-331-FTF | 1 | R167 |  |
| RES CHIP 499 1/16W +1%(0402)EF | CYN | RR0510S-4990-FTF | 2 | R251,R287 |  |
| RES CHIP 665 1/16W +1%(0402)EF | CYN | RR0510S-6650-FTF | 1 | R793 |  |
| RES CHIP 750 1/16W +1%(0402)EF | WTC | WR04X7500FTR | 8 | R597,R598,R599,R600,R601,R602,R603,R604 |  |
| RES CHIP 1K 1/16W +1%(0402)EF | CYN | RR0510S-102-FTF | 21 | R4,R5,R15,R188,R189,R190,R191,R194,R195,R196,R197,R210,R324,R325,R419,R735,R736,R775,R795,R796,R855 |  |
| RES CHIP 1.69K 1/16W +1%(0402)EF | CYN | RR0510S-1691-FTF | 1 | R791 |  |
| RES CHIP 1.8K 1/16W +-1%(0402)EF | CYN | RR0510S-182-FTF | 2 | R244,R245 |  |
| RES CHIP 2K 1/16W +1%(0402)EF | CYN | RR0510S-202-FTF | 16 | R74,R75,R76,R78,R79,R82,R124,R467,R714,R751,R786,R788,R790,R792,R794,R798 |  |
| RES CHIP 2.2K 1/16W +5%(0402)EF | YGO | RC0402JR-072K2P | 21 | R91,R92,R246,R247,R248,R249,R252,R253,R256,R257,R258,R259,R264,R265,R422,R428,R429,R438,R610,R692,R709 |  |
| RES CHIP 2.74K 1/16W +1%(0402)EF | KOA | RK73H1EVTTP2741F | 1 | R235 |  |
| RES CHIP 2.87K 1/16W +1%(0402)EF | CYN | RR0510S-2871-FTF | 2 | R789,R797 |  |
| RES CHIP 4.7K 1/16W +1%(0402)EF | CYN | RR0510S-472-FTF | 84 | R9,R11,R31,R32,R38,R42,R45,R52,R55,R56,R61,R62,R67,R68,R69,R72,R81,R94,R101,R103,R116,R161,R163,R169,R181,R212,R238,R239,R240,R241,R268,R269,R285,R291,R298,R299,R319,R376,R416,R430,R446,R452,R462,R488,R490,R492,R557,R558,R563,R586,R592,R607,R608,R621,R624,R625,R627,R630,R667,R683,R706,R717,R730,R738,R739,R740,R741,R749,R758,R765,R774,R805,R806,R816,R835,R842,R843,R844,R848,R851,R856,R858,R885,R886 |  |
| RES CHIP 5.36K 1/16W +1%(0402)EF | CYN | RR0510S-5361-FTF | 1 | R787 |  |
| RES CHIP 5.49K 1/16W +1%(0402) EF | YGO | RC0402FR-075K49P | 1 | PR276 |  |
| RES CHIP 8.2K 1/16W +5% (0402) EF | CYN | RR0510S-822-JTF | 3 | R504,R768,R839 |  |
| RES CHIP 10K 1/16W +1%(0402)EF | YGO | RC0402FR-0710KP | 45 | PR241,PR242,PR498,PR500,R50,R54,R59,R126,R136,R145,R149,R203,R204,R206,R211,R226,R227,R230,R254,R255,R260,R261,R262,R288,R289,R295,R306,R383,R403,R404,R406,R464,R497,R508,R521,R523,R677,R716,R808,R809,R810,R814,R815,R866,R297 |  |
| RES CHIP 12K 1/16W +1%(0402)EF | CYN | RR0510S-123-FTF | 2 | R830,R832 |  |
| RES CHIP 12.4K 1/16W +1%(0402)EF | YGO | RC0402FR-0712K4P | 2 | PR526,PR530 |  |
| RES CHIP 15K 1/16W +1%(0402)EF | CYN | RR0510S-153-FTF | 1 | R831 |  |
| RES CHIP 15.8K 1/16W +1% (0402)EF | YGO | RC0402FR-0715K8P | 1 | R785 |  |
| RES CHIP 16.9K 1/16W +1%(0402)EF | WTC | WR04X1692FTR | 1 | R631 |  |
| RES CHIP 20K 1/16W +1%(0402)EF | CYN | RR0510S-203-FTF | 2 | R205,R378 |  |
| RES CHIP 20.5K 1/16W +1%(0402)EF | YGO | RC0402FR-0720K5P | 1 | PR525 |  |
| RES CHIP 25.5K 1/16W +1%(0402)EF | CYN | RR0510S-2552-FTF | 1 | R829 |  |
| RES CHIP 47K 1/16W +1%(0402)EF | YGO | RC0402FR-0747KP | 3 | R290,R312,R776 |  |
| RES CHIP 49.9K 1/16W +1%(0402)EF | CYN | RR0510S-4992-FTF | 2 | R233,R234 |  |
| RES CHIP 56K 1/16W +1%(0402)EF | YGO | RC0402FR-0756KP | 1 | PR534 |  |
| RES CHIP 60.4K 1/16W +1%(0402)EF | CYN | RR0510S-6042-FTF | 1 | PR532 |  |
| RES CHIP 91K 1/16W +1%(0402)EF | YGO | RC0402FR-0791KP | 1 | PR527 |  |
| RES CHIP 100K 1/16W +1%(0402)EF | YGO | RC0402FR-07100KP | 16 | PR522,PR543,R66,R118,R193,R273,R314,R387,R396,R538,R614,R620,R642,R710,R778,R823 |  |
| RES CHIP 150K 1/16W +1%(0402)EF | CYN | RR0510S-154-FTF | 1 | PR496 |  |
| RES CHIP 200K 1/16W +1%(0402)EF | YGO | RC0402FR-07200KP | 1 | R777 |  |
| RES CHIP 470K 1/16W +1%(0402)EF | CYN | RR0510S-474-FTF | 1 | R313 |  |
| RES CHIP 681K 1/16W +1%(0402)EF | RLC | FTT026813FTH | 1 | PR521 |  |
| IND SMD 1UH 20%11A(PCMC063T-1R0MN) | CYN | PCMC063T-1R0MN | 2 | PL31,PL33 |  |
| IND SMD 3.3UH,6A20%(PCMC063T-3R3MN) | CYN | PCMC063T-3R3MN | 1 | PL35 |  |
| IND SMD 4.7UH +20% 10A(PCMB104E-4R7MS) | CYN | PCMB104E-4R7MS | 1 | PL34 |  |
| EMI FILTER BLM18SN220TN1D(22,8000MA) | MUR | BLM18SN220TN1D | 4 | PL4,PL19,PL29,PL32 |  |
| EMI FILTER CHIP BLM18BB470(47,500MA) | MUR | BLM18BB470SN1D | 3 | L28,L29,L30 |  |
| EMI FILTER BLM18EG121SN1D(120.2A) | MUR | BLM18EG121SN1D | 2 | L17,L19 |  |
| EMI FILTER BLM18PG121SN(120,2000MA) | MUR | BLM18PG121SN1D | 14 | L2,L3,L4,L5,L6,L7,L8,L10,L11,L12,L13,L14,L15,L16 |  |
| CONN SMD HEADER 3P 1R MS(P2.54,H9.3) | PRX | 212-H91-03GBR1 | 1 | J1 |  |
| CONN DIP HEADER 8P 1R MS(P2.54,H8.6) | PRX | 210-HP1-080BR1 | 1 | J7 |  |
| CONN SMD HEADER 13P 1R MS(P1.0,H4.3) | ACS | 50228-0130C-V01 | 1 | J8 |  |
| CONN DIP USB3.0 9P 2R FR(P2.0,H7.74) | APL | GSB3111315HR | 1 | J2 |  |
| CONN SMD HOUSING 11P 2R FS(P1,H3.28) | BER | 91920-31111LF | 2 | J5,J10 |  |
| CONN SMD HOUSING 75P 2R FR(P0.5,H6.7) | LTK | NASA0-S6730-TS67 | 1 | J4 |  |
| IC SOCKET SMD 16P(SPI,SOIC)(P1.27,H5.8) | LTS | ACA-SPI-006-P06 | 1 | J40 |  |
| SWITCH TACT DTSAM-63N/K-S-Q-T/R | DIP | DTSAM-63N/K-S-Q-T/R | 3 | SW6,SW7,SW8 |  |
| IC(24P) PCA9555PW(TSSOP)EP | PHI | PCA9555PW | 1 | U40 |  |
| DIODE UCLAMP3311T.TCT(3.3V,SLP1006P2T) | STH | UCLAMP3311T.TCT | 1 | D10 |  |
| NUT SMT M2*0.4 F0T(MBF0T003,3A)STEEL FVT | FVT | MBS6A00101 | 2 | H6,H7 |  |
| NUT SMT MMG BD F0T(MBF0T002,R3A)STEEL | FVT | MBF0T00201 | 1 | H1 |  |
| NUT SCM BEZEL S9S(MBS9S001,REV3A)STL PEF | PEF | MBS9S00101 | 1 | H5 |  |
| NUT SMT M3*4.15 CU F09(MBF09001,REV3B) | ASN | MBF0900101 | 2 | H3,H4 |  |
| IC FLASH(16P)MX25L51245GMI-10G(SOP) | MAX | MX25L51245GMI-10G | 1 | BIOS ON J40 |  |
| M.2HANDLE LATCH H6.7 F0G(JXF0G001,3B)FVT | FVT | JXF0G00101 | 1 | H2 BSM LATCH |  |
| F0T SENSOR BD ASSY |  |  | 1 | On J14 |  |
| CAP CHIP 15P 50V(+-5% C0G 0402) | MUR | GRM1555C1H150J | 3 | C205,C206,C207 |  |
| CAP CHIP 22P 50V(+-5%,NPO,0402) | MUR | GRM1555C1H220J | 2 | C208,C210 |  |
| CAP CHIP 18P 50V(+-5% C0G 0402) | MUR | GRM1555C1H180J | 1 | C209 |  |
| RES CHIP 40.2 1/16W +-1%(0402) | WTC | WR04X40R2FTL | 1 | R138 |  |
| RES CHIP 110 1/16W +-1%(0402)EF | TAI | RM04FTW1100 | 4 | R184,R186,R198,R200 |  |
| RES CHIP 402 1/16W +-1%(0402)EF | WTC | WR04X4020FTR | 1 | R250 |  |
| IC OTHER(5P)SN74LVC1G07DCKR(SOT) | TIC | SN74LVC1G07DCKR | 1 | U44 |  |
